# BASEBOARD_FAB2 (Tioga Pass) — schematic netlist excerpt (pin names and nets, part order shuffled) for the footprints in the layout excerpt that follows; sources: Cadence DE-HDL packaged netlist, KiCad conversion of Wiwynn_Tioga_Pass_MB.brd

C3P19  CAP  0.22UF 16V 10% X7R  pkg 0402  page 107 : A = P3E_CPU0_PE1_SS_TXP<2> ; B = P3E_CPU0_PE1_SS_C_TXP<2>
C2U11  CAP  0.22UF 16V 10% X7R  pkg 0402  page 107 : A = P3E_CPU0_PE1_PCH_RXP<4> ; B = P3E_CPU0_PE1_SS_RXP<4>
C3M22  CAP_A  1.0UF 6.3V 10% X6S  pkg 0402V  page 127 : A = P1V05_PCH_STBY ; B = GND

(kicad_pcb
	(version 20260206)
	(generator "pcbnew")
	(generator_version "10.0")
	(general
		(thickness 1.6)
		(legacy_teardrops no)
	)
	(paper "A4")
	(title_block
		(title "Wiwynn_Tioga_Pass_MB.brd")
		(comment 1 "Tioga Pass / footprints 2670-2672 of 4770")
	)
	(layers
		(0 "F.Cu" signal "TOP")
		(4 "In1.Cu" signal "L2GND")
		(6 "In2.Cu" signal "L3")
		(8 "In3.Cu" signal "L4GND")
		(10 "In4.Cu" signal "L5")
		(12 "In5.Cu" signal "L6GND")
		(14 "In6.Cu" signal "L7VCC")
		(16 "In7.Cu" signal "L8VCC")
		(18 "In8.Cu" signal "L9GND")
		(20 "In9.Cu" signal "L10")
		(22 "In10.Cu" signal "L11GND")
		(24 "In11.Cu" signal "L12")
		(26 "In12.Cu" signal "L13GND")
		(2 "B.Cu" signal "BOTTOM")
		(9 "F.Adhes" user "F.Adhesive")
		(11 "B.Adhes" user "B.Adhesive")
		(13 "F.Paste" user "Package Geometry/Pastemask Top")
		(15 "B.Paste" user "Package Geometry/Pastemask Bottom")
		(5 "F.SilkS" user "Ref Des/Silkscreen Top")
		(7 "B.SilkS" user "Ref Des/Silkscreen Bottom")
		(1 "F.Mask" user "Board Geometry/Soldermask Top")
		(3 "B.Mask" user "Board Geometry/Soldermask Bottom")
		(17 "Dwgs.User" user "User.Drawings")
		(19 "Cmts.User" user "User.Comments")
		(21 "Eco1.User" user "User.Eco1")
		(23 "Eco2.User" user "User.Eco2")
		(25 "Edge.Cuts" user "Board Geometry/Outline")
		(27 "Margin" user)
		(31 "F.CrtYd" user "Package Geometry/Place Bound Top")
		(29 "B.CrtYd" user "Package Geometry/Place Bound Bottom")
		(35 "F.Fab" user "Ref Des/Assembly Top")
		(33 "B.Fab" user "Ref Des/Assembly Bottom")
	)
	(footprint ""
		(layer "B.Cu")
		(at 344.522806 -61.257434)
		(property "Reference" "C2U11"
			(at 0 0 0)
			(layer "B.SilkS")
			(hide yes)
			(effects
				(font
					(size 1.27 1.27)
				)
				(justify mirror)
			)
		)
		(property "Value" ""
			(at 0 0 0)
			(layer "B.Fab")
			(effects
				(font
					(size 1.27 1.27)
				)
				(justify mirror)
			)
		)
		(duplicate_pad_numbers_are_jumpers no)
		(fp_poly
			(pts
				(xy -0.3048 -0.1016) (xy -0.3048 0.9906) (xy 0.3048 0.9906) (xy 0.3048 -0.1016)
			)
			(stroke
				(width 0)
				(type default)
			)
			(fill no)
			(layer "B.CrtYd")
		)
		(fp_line
			(start -0.3048 -0.1016)
			(end 0.3048 -0.1016)
			(stroke
				(width 0.1)
				(type default)
			)
			(layer "B.Fab")
		)
		(fp_line
			(start -0.3048 0.9906)
			(end -0.3048 -0.1016)
			(stroke
				(width 0.1)
				(type default)
			)
			(layer "B.Fab")
		)
		(fp_line
			(start 0.3048 -0.1016)
			(end 0.3048 0.9906)
			(stroke
				(width 0.1)
				(type default)
			)
			(layer "B.Fab")
		)
		(fp_line
			(start 0.3048 0.9906)
			(end -0.3048 0.9906)
			(stroke
				(width 0.1)
				(type default)
			)
			(layer "B.Fab")
		)
		(pad "1" smd rect
			(at 0 0 180)
			(size 0.508 0.508)
			(layers "B.Cu" "B.Mask" "B.Paste")
			(net "P3E_CPU0_PE1_PCH_RXP<4>")
		)
		(pad "2" smd rect
			(at 0 0.889 180)
			(size 0.508 0.508)
			(layers "B.Cu" "B.Mask" "B.Paste")
			(net "P3E_CPU0_PE1_SS_RXP<4>")
		)
		(zone
			(layer "B.Cu")
			(hatch none 0.5)
			(connect_pads
				(clearance 0)
			)
			(min_thickness 0.25)
			(keepout
				(tracks allowed)
				(vias not_allowed)
				(pads allowed)
				(copperpour not_allowed)
				(footprints allowed)
			)
			(placement
				(enabled no)
				(sheetname "")
			)
			(fill
				(thermal_gap 0.5)
				(thermal_bridge_width 0.5)
				(island_removal_mode 0)
			)
			(polygon
				(pts
					(xy 344.776806 -61.003434) (xy 344.268806 -61.003434) (xy 344.268806 -60.622434) (xy 344.776806 -60.622434)
				)
			)
		)
	)
	(footprint ""
		(layer "B.Cu")
		(at 370.967 -135.636 180)
		(property "Reference" "C3M22"
			(at 0 0 0)
			(layer "B.SilkS")
			(hide yes)
			(effects
				(font
					(size 1.27 1.27)
				)
				(justify mirror)
			)
		)
		(property "Value" ""
			(at 0 0 0)
			(layer "B.Fab")
			(effects
				(font
					(size 1.27 1.27)
				)
				(justify mirror)
			)
		)
		(duplicate_pad_numbers_are_jumpers no)
		(fp_poly
			(pts
				(xy -0.3048 -0.1016) (xy -0.3048 0.9906) (xy 0.3048 0.9906) (xy 0.3048 -0.1016)
			)
			(stroke
				(width 0)
				(type default)
			)
			(fill no)
			(layer "B.CrtYd")
		)
		(fp_line
			(start 0.3048 0.9906)
			(end -0.3048 0.9906)
			(stroke
				(width 0.1)
				(type default)
			)
			(layer "B.Fab")
		)
		(fp_line
			(start 0.3048 -0.1016)
			(end 0.3048 0.9906)
			(stroke
				(width 0.1)
				(type default)
			)
			(layer "B.Fab")
		)
		(fp_line
			(start -0.3048 0.9906)
			(end -0.3048 -0.1016)
			(stroke
				(width 0.1)
				(type default)
			)
			(layer "B.Fab")
		)
		(fp_line
			(start -0.3048 -0.1016)
			(end 0.3048 -0.1016)
			(stroke
				(width 0.1)
				(type default)
			)
			(layer "B.Fab")
		)
		(pad "1" smd rect
			(at 0 0)
			(size 0.508 0.508)
			(layers "B.Cu" "B.Mask" "B.Paste")
			(net "P1V05_PCH_STBY")
		)
		(pad "2" smd rect
			(at 0 0.889)
			(size 0.508 0.508)
			(layers "B.Cu" "B.Mask" "B.Paste")
			(net "GND")
		)
		(zone
			(layer "B.Cu")
			(hatch none 0.5)
			(connect_pads
				(clearance 0)
			)
			(min_thickness 0.25)
			(keepout
				(tracks not_allowed)
				(vias allowed)
				(pads allowed)
				(copperpour not_allowed)
				(footprints allowed)
			)
			(placement
				(enabled no)
				(sheetname "")
			)
			(fill
				(thermal_gap 0.5)
				(thermal_bridge_width 0.5)
				(island_removal_mode 0)
			)
			(polygon
				(pts
					(xy 370.713 -136.271) (xy 371.221 -136.271) (xy 371.221 -135.89) (xy 370.713 -135.89)
				)
			)
		)
		(zone
			(layer "B.Cu")
			(hatch none 0.5)
			(connect_pads
				(clearance 0)
			)
			(min_thickness 0.25)
			(keepout
				(tracks allowed)
				(vias not_allowed)
				(pads allowed)
				(copperpour not_allowed)
				(footprints allowed)
			)
			(placement
				(enabled no)
				(sheetname "")
			)
			(fill
				(thermal_gap 0.5)
				(thermal_bridge_width 0.5)
				(island_removal_mode 0)
			)
			(polygon
				(pts
					(xy 370.713 -135.89) (xy 371.221 -135.89) (xy 371.221 -136.271) (xy 370.713 -136.271)
				)
			)
		)
	)
	(footprint ""
		(layer "B.Cu")
		(at 344.435176 -77.694536)
		(property "Reference" "C3P19"
			(at 0 0 0)
			(layer "B.SilkS")
			(hide yes)
			(effects
				(font
					(size 1.27 1.27)
				)
				(justify mirror)
			)
		)
		(property "Value" ""
			(at 0 0 0)
			(layer "B.Fab")
			(effects
				(font
					(size 1.27 1.27)
				)
				(justify mirror)
			)
		)
		(duplicate_pad_numbers_are_jumpers no)
		(fp_poly
			(pts
				(xy -0.3048 -0.1016) (xy -0.3048 0.9906) (xy 0.3048 0.9906) (xy 0.3048 -0.1016)
			)
			(stroke
				(width 0)
				(type default)
			)
			(fill no)
			(layer "B.CrtYd")
		)
		(fp_line
			(start -0.3048 -0.1016)
			(end 0.3048 -0.1016)
			(stroke
				(width 0.1)
				(type default)
			)
			(layer "B.Fab")
		)
		(fp_line
			(start -0.3048 0.9906)
			(end -0.3048 -0.1016)
			(stroke
				(width 0.1)
				(type default)
			)
			(layer "B.Fab")
		)
		(fp_line
			(start 0.3048 -0.1016)
			(end 0.3048 0.9906)
			(stroke
				(width 0.1)
				(type default)
			)
			(layer "B.Fab")
		)
		(fp_line
			(start 0.3048 0.9906)
			(end -0.3048 0.9906)
			(stroke
				(width 0.1)
				(type default)
			)
			(layer "B.Fab")
		)
		(pad "1" smd rect
			(at 0 0 180)
			(size 0.508 0.508)
			(layers "B.Cu" "B.Mask" "B.Paste")
			(net "P3E_CPU0_PE1_SS_TXP<2>")
		)
		(pad "2" smd rect
			(at 0 0.889 180)
			(size 0.508 0.508)
			(layers "B.Cu" "B.Mask" "B.Paste")
			(net "P3E_CPU0_PE1_SS_C_TXP<2>")
		)
		(zone
			(layer "B.Cu")
			(hatch none 0.5)
			(connect_pads
				(clearance 0)
			)
			(min_thickness 0.25)
			(keepout
				(tracks allowed)
				(vias not_allowed)
				(pads allowed)
				(copperpour not_allowed)
				(footprints allowed)
			)
			(placement
				(enabled no)
				(sheetname "")
			)
			(fill
				(thermal_gap 0.5)
				(thermal_bridge_width 0.5)
				(island_removal_mode 0)
			)
			(polygon
				(pts
					(xy 344.689176 -77.440536) (xy 344.181176 -77.440536) (xy 344.181176 -77.059536) (xy 344.689176 -77.059536)
				)
			)
		)
	)
)
